FILE_TYPE = MULTI_PHYS_TABLE;

PART 'PICOPROBE_BXA'

{========================================================================================}
:VALUE         | PART_TYPE | MATERIAL | PART_NUMBER    = STANDARD | LIFECYCLE | PART_NUMBER | JEDEC_TYPE           | ALT_SYMBOLS | DESCRIPTION                         | MANUFTR | MANUF_PN | RD_CMPLS_LVL | CMPLS_LVL | CLASS | DIP_SMD | FROM_PJ | DATA                     | FP_ECN                    | EE_CHECK_LIST | STATUS | PSL | PREFERENCE | CREATOR | CREATEDAY  | ESD_CDM | ESD_HBM | ESD_MM | MSD | PIN_LENGTH_LONG_PIN | PIN_LENGTH_SHORT_PIN ;
{========================================================================================}
 'DELTA-L 4.0' | 'SMLF'    | 'EMPTY'  | 'TP33'(!)      = ''       | ''        | 'TP33'      |'TRIANG_LAUNCH_3PXB'| ''          | 'Probe for DELTA-L 4.0 measurement' | ''      | ''       | ''           | ''        | 'IO'  | ''      | ''      | 'TRIANG_LAUNCH_3PXB.pdf' | 'TRIANG_LAUNCH_3PXB.xlsx' | ''            | ''     | ''  | ''         | ''      | '20200107' | ''      | ''      | ''     | ''  | ''                  | ''                  

END_PART

END.

